(kicad_pcb
	(version 20260206)
	(generator "pcbnew")
	(generator_version "10.0")
	(general
		(thickness 1.6)
		(legacy_teardrops no)
	)
	(paper "A4")
	(title_block
		(title "Wiwynn_Tioga_Pass_MB.brd")
		(comment 1 "Tioga Pass / footprints 1442-1446 of 4770")
	)
	(layers
		(0 "F.Cu" signal "TOP")
		(4 "In1.Cu" signal "L2GND")
		(6 "In2.Cu" signal "L3")
		(8 "In3.Cu" signal "L4GND")
		(10 "In4.Cu" signal "L5")
		(12 "In5.Cu" signal "L6GND")
		(14 "In6.Cu" signal "L7VCC")
		(16 "In7.Cu" signal "L8VCC")
		(18 "In8.Cu" signal "L9GND")
		(20 "In9.Cu" signal "L10")
		(22 "In10.Cu" signal "L11GND")
		(24 "In11.Cu" signal "L12")
		(26 "In12.Cu" signal "L13GND")
		(2 "B.Cu" signal "BOTTOM")
		(9 "F.Adhes" user "F.Adhesive")
		(11 "B.Adhes" user "B.Adhesive")
		(13 "F.Paste" user "Package Geometry/Pastemask Top")
		(15 "B.Paste" user "Package Geometry/Pastemask Bottom")
		(5 "F.SilkS" user "Ref Des/Silkscreen Top")
		(7 "B.SilkS" user "Ref Des/Silkscreen Bottom")
		(1 "F.Mask" user "Board Geometry/Soldermask Top")
		(3 "B.Mask" user "Board Geometry/Soldermask Bottom")
		(17 "Dwgs.User" user "User.Drawings")
		(19 "Cmts.User" user "User.Comments")
		(21 "Eco1.User" user "User.Eco1")
		(23 "Eco2.User" user "User.Eco2")
		(25 "Edge.Cuts" user "Board Geometry/Outline")
		(27 "Margin" user)
		(31 "F.CrtYd" user "Package Geometry/Place Bound Top")
		(29 "B.CrtYd" user "Package Geometry/Place Bound Bottom")
		(35 "F.Fab" user "Ref Des/Assembly Top")
		(33 "B.Fab" user "Ref Des/Assembly Bottom")
	)
	(footprint ""
		(layer "F.Cu")
		(at 198.925434 -89.551764 90)
		(property "Reference" "EU4C2"
			(at 3.309366 -1.618234 0)
			(unlocked yes)
			(layer "F.SilkS")
			(effects
				(font
					(size 0.7874 0.5842)
					(thickness 0.1524)
				)
			)
		)
		(property "Value" ""
			(at 0 0 90)
			(layer "F.Fab")
			(effects
				(font
					(size 1.27 1.27)
				)
			)
		)
		(duplicate_pad_numbers_are_jumpers no)
		(fp_line
			(start 2.9718 -3.5052)
			(end 2.9718 3.429)
			(stroke
				(width 0.1524)
				(type default)
			)
			(layer "F.SilkS")
		)
		(fp_line
			(start -3.0099 -3.5052)
			(end 2.9718 -3.5052)
			(stroke
				(width 0.1524)
				(type default)
			)
			(layer "F.SilkS")
		)
		(fp_line
			(start 2.9718 3.429)
			(end -3.0099 3.429)
			(stroke
				(width 0.1524)
				(type default)
			)
			(layer "F.SilkS")
		)
		(fp_line
			(start -3.0099 3.429)
			(end -3.0099 -3.5052)
			(stroke
				(width 0.1524)
				(type default)
			)
			(layer "F.SilkS")
		)
		(fp_circle
			(center -3.373374 -3.160522)
			(end -3.373374 -3.033522)
			(stroke
				(width 0.254)
				(type default)
			)
			(fill no)
			(layer "F.SilkS")
		)
		(fp_poly
			(pts
				(xy -2.9972 -3.4925) (xy -2.9972 -2.6924) (xy -2.1971 -3.4925)
			)
			(stroke
				(width 0)
				(type default)
			)
			(fill yes)
			(layer "F.SilkS")
		)
		(fp_poly
			(pts
				(xy -2.549906 -3.050032) (xy -2.549906 3.050032) (xy 2.549906 3.050032) (xy 2.549906 -3.050032)
			)
			(stroke
				(width 0)
				(type default)
			)
			(fill no)
			(layer "F.CrtYd")
		)
		(fp_line
			(start 2.549906 -3.050032)
			(end 2.549906 3.050032)
			(stroke
				(width 0.1)
				(type default)
			)
			(layer "F.Fab")
		)
		(fp_line
			(start -2.549906 -3.050032)
			(end 2.549906 -3.050032)
			(stroke
				(width 0.1)
				(type default)
			)
			(layer "F.Fab")
		)
		(fp_line
			(start 2.549906 3.050032)
			(end -2.549906 3.050032)
			(stroke
				(width 0.1)
				(type default)
			)
			(layer "F.Fab")
		)
		(fp_line
			(start -2.549906 3.050032)
			(end -2.549906 -3.050032)
			(stroke
				(width 0.1)
				(type default)
			)
			(layer "F.Fab")
		)
		(fp_circle
			(center -3.057398 -2.678684)
			(end -3.057398 -2.551684)
			(stroke
				(width 0.254)
				(type default)
			)
			(fill no)
			(layer "F.Fab")
		)
		(pad "1" smd rect
			(at -2.39522 -2.279904 90)
			(size 0.7112 0.254)
			(layers "F.Cu" "F.Mask" "F.Paste")
			(net "PVCCIN_CPU0")
		)
		(pad "2" smd rect
			(at -2.39522 -1.83007 90)
			(size 0.7112 0.254)
			(layers "F.Cu" "F.Mask" "F.Paste")
			(net "GND")
		)
		(pad "3" smd rect
			(at -2.39522 -1.379982 90)
			(size 0.7112 0.254)
			(layers "F.Cu" "F.Mask" "F.Paste")
			(net "VR_PVCCIN_CPU0_PH5_VCIN")
		)
		(pad "4" smd rect
			(at -2.39522 -0.929894 90)
			(size 0.7112 0.254)
			(layers "F.Cu" "F.Mask" "F.Paste")
			(net "P5V_STBY")
		)
		(pad "5" smd rect
			(at -2.39522 -0.48006 90)
			(size 0.7112 0.254)
			(layers "F.Cu" "F.Mask" "F.Paste")
			(net "GND")
		)
		(pad "6" smd rect
			(at -2.39522 -0.029972 90)
			(size 0.7112 0.254)
			(layers "F.Cu" "F.Mask" "F.Paste")
			(net "TP_PVCCIN_CPU0_PH5_GL_0")
		)
		(pad "7" smd custom
			(at 0.016764 1.145032 90)
			(size 0.53975 0.53975)
			(layers "F.Cu" "F.Mask" "F.Paste")
			(net "GND")
			(options
				(clearance outline)
				(anchor circle)
			)
			(primitives
				(gr_poly
					(pts
						(xy -2.7051 1.0795) (xy -2.7051 -0.3683) (xy -0.9271 -0.3683) (xy -0.9271 -1.0795) (xy 2.7051 -1.0795)
						(xy 2.7051 1.0795)
					)
					(width 0)
					(fill yes)
				)
			)
		)
		(pad "10" smd rect
			(at -0.008382 2.874772 90)
			(size 4.3434 0.6096)
			(layers "F.Cu" "F.Mask" "F.Paste")
			(net "VR_PVCCIN_CPU0_PHASE5")
		)
		(pad "25" smd rect
			(at 1.548384 -1.283208 90)
			(size 2.3368 2.0066)
			(layers "F.Cu" "F.Mask" "F.Paste")
			(net "VR_FET_SW_P12V_STBY_PVCCIN_CPU0")
		)
		(pad "30" smd rect
			(at 2.050034 -2.895092 90)
			(size 0.254 0.7112)
			(layers "F.Cu" "F.Mask" "F.Paste")
			(net "VR_FET_SW_P12V_STBY_PVCCIN_CPU0")
		)
		(pad "31" smd rect
			(at 1.599946 -2.895092 90)
			(size 0.254 0.7112)
			(layers "F.Cu" "F.Mask" "F.Paste")
			(net "Net_365")
		)
		(pad "32" smd rect
			(at 1.150112 -2.895092 90)
			(size 0.254 0.7112)
			(layers "F.Cu" "F.Mask" "F.Paste")
			(net "VR_PVCCIN_CPU0_PH5_PHASE")
		)
		(pad "33" smd rect
			(at 0.700024 -2.895092 90)
			(size 0.254 0.7112)
			(layers "F.Cu" "F.Mask" "F.Paste")
			(net "VR_PVCCIN_CPU0_PH5_BOOT_R")
		)
		(pad "34" smd rect
			(at 0.249936 -2.895092 90)
			(size 0.254 0.7112)
			(layers "F.Cu" "F.Mask" "F.Paste")
			(net "VR_PVCCIN_CPU0_PWM5")
		)
		(pad "35" smd rect
			(at -0.199898 -2.895092 90)
			(size 0.254 0.7112)
			(layers "F.Cu" "F.Mask" "F.Paste")
			(net "P5V_STBY")
		)
		(pad "36" smd rect
			(at -0.649986 -2.895092 90)
			(size 0.254 0.7112)
			(layers "F.Cu" "F.Mask" "F.Paste")
			(net "A_TSENSE_PVCCIN_CPU0")
		)
		(pad "37" smd rect
			(at -1.100074 -2.895092 90)
			(size 0.254 0.7112)
			(layers "F.Cu" "F.Mask" "F.Paste")
			(net "VR_PVCCIN_CPU0_PH5_OCSET")
		)
		(pad "38" smd rect
			(at -1.549908 -2.895092 90)
			(size 0.254 0.7112)
			(layers "F.Cu" "F.Mask" "F.Paste")
			(net "ISENSE_PVCCIN_CPU0_PH5_IMON")
		)
		(pad "39" smd rect
			(at -1.999996 -2.895092 90)
			(size 0.254 0.7112)
			(layers "F.Cu" "F.Mask" "F.Paste")
			(net "VR_PVCCIN_CPU0_AIREF5")
		)
		(pad "40" smd rect
			(at -0.871728 -1.283208 90)
			(size 1.8034 2.0066)
			(layers "F.Cu" "F.Mask" "F.Paste")
			(net "GND")
		)
		(pad "41" smd rect
			(at -1.533906 0.247904 90)
			(size 0.508 0.3556)
			(layers "F.Cu" "F.Mask" "F.Paste")
			(net "TP_PVCCIN_CPU0_PH5_GL_1")
		)
	)
	(footprint ""
		(layer "F.Cu")
		(at 491.49 -39.0144 -90)
		(property "Reference" "R9F5"
			(at 0 0 270)
			(layer "F.SilkS")
			(hide yes)
			(effects
				(font
					(size 1.27 1.27)
				)
			)
		)
		(property "Value" ""
			(at 0 0 270)
			(layer "F.Fab")
			(effects
				(font
					(size 1.27 1.27)
				)
			)
		)
		(duplicate_pad_numbers_are_jumpers no)
		(fp_poly
			(pts
				(xy -0.2794 -0.1016) (xy 0.2794 -0.1016) (xy 0.2794 0.9906) (xy -0.2794 0.9906)
			)
			(stroke
				(width 0)
				(type default)
			)
			(fill no)
			(layer "F.CrtYd")
		)
		(fp_line
			(start -0.2794 0.9906)
			(end 0.2794 0.9906)
			(stroke
				(width 0.1)
				(type default)
			)
			(layer "F.Fab")
		)
		(fp_line
			(start 0.2794 0.9906)
			(end 0.2794 -0.1016)
			(stroke
				(width 0.1)
				(type default)
			)
			(layer "F.Fab")
		)
		(fp_line
			(start -0.2794 -0.1016)
			(end -0.2794 0.9906)
			(stroke
				(width 0.1)
				(type default)
			)
			(layer "F.Fab")
		)
		(fp_line
			(start 0.2794 -0.1016)
			(end -0.2794 -0.1016)
			(stroke
				(width 0.1)
				(type default)
			)
			(layer "F.Fab")
		)
		(pad "1" smd rect
			(at 0 0 270)
			(size 0.508 0.508)
			(layers "F.Cu" "F.Mask" "F.Paste")
			(net "P3V3_STBY")
		)
		(pad "2" smd rect
			(at 0 0.889 270)
			(size 0.508 0.508)
			(layers "F.Cu" "F.Mask" "F.Paste")
			(net "PU_SPRV_LAN_PWR_GOOD")
		)
		(zone
			(layer "F.Cu")
			(hatch none 0.5)
			(connect_pads
				(clearance 0)
			)
			(min_thickness 0.25)
			(keepout
				(tracks not_allowed)
				(vias allowed)
				(pads allowed)
				(copperpour not_allowed)
				(footprints allowed)
			)
			(placement
				(enabled no)
				(sheetname "")
			)
			(fill
				(thermal_gap 0.5)
				(thermal_bridge_width 0.5)
				(island_removal_mode 0)
			)
			(polygon
				(pts
					(xy 490.855 -39.2684) (xy 490.855 -38.7604) (xy 491.236 -38.7604) (xy 491.236 -39.2684)
				)
			)
		)
		(zone
			(layer "F.Cu")
			(hatch none 0.5)
			(connect_pads
				(clearance 0)
			)
			(min_thickness 0.25)
			(keepout
				(tracks allowed)
				(vias not_allowed)
				(pads allowed)
				(copperpour not_allowed)
				(footprints allowed)
			)
			(placement
				(enabled no)
				(sheetname "")
			)
			(fill
				(thermal_gap 0.5)
				(thermal_bridge_width 0.5)
				(island_removal_mode 0)
			)
			(polygon
				(pts
					(xy 491.236 -39.2684) (xy 491.236 -38.7604) (xy 490.855 -38.7604) (xy 490.855 -39.2684)
				)
			)
		)
	)
	(footprint ""
		(layer "F.Cu")
		(at 369.7224 -108.6104)
		(property "Reference" "R7C1"
			(at 0 0 0)
			(layer "F.SilkS")
			(hide yes)
			(effects
				(font
					(size 1.27 1.27)
				)
			)
		)
		(property "Value" ""
			(at 0 0 0)
			(layer "F.Fab")
			(effects
				(font
					(size 1.27 1.27)
				)
			)
		)
		(duplicate_pad_numbers_are_jumpers no)
		(fp_poly
			(pts
				(xy -0.4953 -0.2032) (xy 0.4953 -0.2032) (xy 0.4953 1.6002) (xy -0.4953 1.6002)
			)
			(stroke
				(width 0)
				(type default)
			)
			(fill no)
			(layer "F.CrtYd")
		)
		(fp_line
			(start -0.4953 -0.2032)
			(end 0.4953 -0.2032)
			(stroke
				(width 0.1)
				(type default)
			)
			(layer "F.Fab")
		)
		(fp_line
			(start -0.4953 1.6002)
			(end -0.4953 -0.2032)
			(stroke
				(width 0.1)
				(type default)
			)
			(layer "F.Fab")
		)
		(fp_line
			(start 0.4953 -0.2032)
			(end 0.4953 1.6002)
			(stroke
				(width 0.1)
				(type default)
			)
			(layer "F.Fab")
		)
		(fp_line
			(start 0.4953 1.6002)
			(end -0.4953 1.6002)
			(stroke
				(width 0.1)
				(type default)
			)
			(layer "F.Fab")
		)
		(pad "1" smd rect
			(at 0 0)
			(size 0.762 0.889)
			(layers "F.Cu" "F.Mask" "F.Paste")
			(net "XTAL_PCH_48M_IN")
		)
		(pad "2" smd rect
			(at 0 1.397)
			(size 0.762 0.889)
			(layers "F.Cu" "F.Mask" "F.Paste")
			(net "XTAL_PCH_48M_OUT")
		)
		(zone
			(layer "F.Cu")
			(hatch none 0.5)
			(connect_pads
				(clearance 0)
			)
			(min_thickness 0.25)
			(keepout
				(tracks not_allowed)
				(vias allowed)
				(pads allowed)
				(copperpour not_allowed)
				(footprints allowed)
			)
			(placement
				(enabled no)
				(sheetname "")
			)
			(fill
				(thermal_gap 0.5)
				(thermal_bridge_width 0.5)
				(island_removal_mode 0)
			)
			(polygon
				(pts
					(xy 369.3414 -107.6579) (xy 370.1034 -107.6579) (xy 370.1034 -108.1659) (xy 369.3414 -108.1659)
				)
			)
		)
		(zone
			(layer "F.Cu")
			(hatch none 0.5)
			(connect_pads
				(clearance 0)
			)
			(min_thickness 0.25)
			(keepout
				(tracks allowed)
				(vias not_allowed)
				(pads allowed)
				(copperpour not_allowed)
				(footprints allowed)
			)
			(placement
				(enabled no)
				(sheetname "")
			)
			(fill
				(thermal_gap 0.5)
				(thermal_bridge_width 0.5)
				(island_removal_mode 0)
			)
			(polygon
				(pts
					(xy 370.1034 -107.6579) (xy 370.1034 -108.1659) (xy 369.3414 -108.1659) (xy 369.3414 -107.6579)
				)
			)
		)
	)
	(footprint ""
		(layer "F.Cu")
		(at 394.462 -41.3766)
		(property "Reference" "R25W182"
			(at -0.8382 -0.67818 0)
			(unlocked yes)
			(layer "F.SilkS")
			(effects
				(font
					(size 0.4064 0.254)
					(thickness 0.1524)
				)
				(justify left)
			)
		)
		(property "Value" ""
			(at 0 0 0)
			(layer "F.Fab")
			(effects
				(font
					(size 1.27 1.27)
				)
			)
		)
		(duplicate_pad_numbers_are_jumpers no)
		(fp_poly
			(pts
				(xy -0.2794 -0.1016) (xy 0.2794 -0.1016) (xy 0.2794 0.9906) (xy -0.2794 0.9906)
			)
			(stroke
				(width 0)
				(type default)
			)
			(fill no)
			(layer "F.CrtYd")
		)
		(fp_line
			(start -0.2794 -0.1016)
			(end -0.2794 0.9906)
			(stroke
				(width 0.1)
				(type default)
			)
			(layer "F.Fab")
		)
		(fp_line
			(start -0.2794 0.9906)
			(end 0.2794 0.9906)
			(stroke
				(width 0.1)
				(type default)
			)
			(layer "F.Fab")
		)
		(fp_line
			(start 0.2794 -0.1016)
			(end -0.2794 -0.1016)
			(stroke
				(width 0.1)
				(type default)
			)
			(layer "F.Fab")
		)
		(fp_line
			(start 0.2794 0.9906)
			(end 0.2794 -0.1016)
			(stroke
				(width 0.1)
				(type default)
			)
			(layer "F.Fab")
		)
		(pad "1" smd rect
			(at 0 0)
			(size 0.508 0.508)
			(layers "F.Cu" "F.Mask" "F.Paste")
			(net "XDP_SYSPWROK")
		)
		(pad "2" smd rect
			(at 0 0.889)
			(size 0.508 0.508)
			(layers "F.Cu" "F.Mask" "F.Paste")
			(net "PWRGD_SYS_PWROK")
		)
		(zone
			(layer "F.Cu")
			(hatch none 0.5)
			(connect_pads
				(clearance 0)
			)
			(min_thickness 0.25)
			(keepout
				(tracks allowed)
				(vias not_allowed)
				(pads allowed)
				(copperpour not_allowed)
				(footprints allowed)
			)
			(placement
				(enabled no)
				(sheetname "")
			)
			(fill
				(thermal_gap 0.5)
				(thermal_bridge_width 0.5)
				(island_removal_mode 0)
			)
			(polygon
				(pts
					(xy 394.208 -41.1226) (xy 394.716 -41.1226) (xy 394.716 -40.7416) (xy 394.208 -40.7416)
				)
			)
		)
		(zone
			(layer "F.Cu")
			(hatch none 0.5)
			(connect_pads
				(clearance 0)
			)
			(min_thickness 0.25)
			(keepout
				(tracks not_allowed)
				(vias allowed)
				(pads allowed)
				(copperpour not_allowed)
				(footprints allowed)
			)
			(placement
				(enabled no)
				(sheetname "")
			)
			(fill
				(thermal_gap 0.5)
				(thermal_bridge_width 0.5)
				(island_removal_mode 0)
			)
			(polygon
				(pts
					(xy 394.208 -40.7416) (xy 394.716 -40.7416) (xy 394.716 -41.1226) (xy 394.208 -41.1226)
				)
			)
		)
	)
	(footprint ""
		(layer "F.Cu")
		(at 338.836 -15.494 -90)
		(property "Reference" "R7G4"
			(at 0 0 270)
			(layer "F.SilkS")
			(hide yes)
			(effects
				(font
					(size 1.27 1.27)
				)
			)
		)
		(property "Value" ""
			(at 0 0 270)
			(layer "F.Fab")
			(effects
				(font
					(size 1.27 1.27)
				)
			)
		)
		(duplicate_pad_numbers_are_jumpers no)
		(fp_rect
			(start 0.2794 0.9906)
			(end -0.2794 -0.1016)
			(stroke
				(width 0)
				(type default)
			)
			(fill no)
			(layer "F.CrtYd")
		)
		(fp_line
			(start -0.2794 0.9906)
			(end 0.2794 0.9906)
			(stroke
				(width 0.1)
				(type default)
			)
			(layer "F.Fab")
		)
		(fp_line
			(start 0.2794 0.9906)
			(end 0.2794 -0.1016)
			(stroke
				(width 0.1)
				(type default)
			)
			(layer "F.Fab")
		)
		(fp_line
			(start -0.2794 -0.1016)
			(end -0.2794 0.9906)
			(stroke
				(width 0.1)
				(type default)
			)
			(layer "F.Fab")
		)
		(fp_line
			(start 0.2794 -0.1016)
			(end -0.2794 -0.1016)
			(stroke
				(width 0.1)
				(type default)
			)
			(layer "F.Fab")
		)
		(pad "1" smd rect
			(at 0 0 270)
			(size 0.508 0.508)
			(layers "F.Cu" "F.Mask" "F.Paste")
			(net "SVID_ALERT_PVDDQ_ABC")
		)
		(pad "2" smd rect
			(at 0 0.889 270)
			(size 0.508 0.508)
			(layers "F.Cu" "F.Mask" "F.Paste")
			(net "SVID_ALERT1_CPU0_R_N")
		)
		(zone
			(layer "F.Cu")
			(hatch none 0.5)
			(connect_pads
				(clearance 0)
			)
			(min_thickness 0.25)
			(keepout
				(tracks not_allowed)
				(vias allowed)
				(pads allowed)
				(copperpour not_allowed)
				(footprints allowed)
			)
			(placement
				(enabled no)
				(sheetname "")
			)
			(fill
				(thermal_gap 0.5)
				(thermal_bridge_width 0.5)
				(island_removal_mode 0)
			)
			(polygon
				(pts
					(xy 338.201 -15.24) (xy 338.582 -15.24) (xy 338.582 -15.748) (xy 338.201 -15.748)
				)
			)
		)
		(zone
			(layer "F.Cu")
			(hatch none 0.5)
			(connect_pads
				(clearance 0)
			)
			(min_thickness 0.25)
			(keepout
				(tracks allowed)
				(vias not_allowed)
				(pads allowed)
				(copperpour not_allowed)
				(footprints allowed)
			)
			(placement
				(enabled no)
				(sheetname "")
			)
			(fill
				(thermal_gap 0.5)
				(thermal_bridge_width 0.5)
				(island_removal_mode 0)
			)
			(polygon
				(pts
					(xy 338.201 -15.24) (xy 338.582 -15.24) (xy 338.582 -15.748) (xy 338.201 -15.748)
				)
			)
		)
	)
)
